(kicad_pcb
	(version 20241229)
	(generator "pcbnew")
	(generator_version "9.0")
	(general
		(thickness 1.59)
		(legacy_teardrops no)
	)
	(paper "A3")
	(title_block
		(title "usb-c-power-adapter")
		(date "2025-06-24")
		(rev "1.1.2")
		(company "Antmicro")
		(comment 9 "footprints 109-113 of 122")
	)
	(layers
		(0 "F.Cu" signal)
		(4 "In1.Cu" signal)
		(6 "In2.Cu" signal)
		(2 "B.Cu" signal)
		(9 "F.Adhes" user "F.Adhesive")
		(11 "B.Adhes" user "B.Adhesive")
		(13 "F.Paste" user)
		(15 "B.Paste" user)
		(5 "F.SilkS" user "F.Silkscreen")
		(7 "B.SilkS" user "B.Silkscreen")
		(1 "F.Mask" user)
		(3 "B.Mask" user)
		(17 "Dwgs.User" user "User.Drawings")
		(19 "Cmts.User" user "User.Comments")
		(21 "Eco1.User" user "User.Eco1")
		(23 "Eco2.User" user "User.Eco2")
		(25 "Edge.Cuts" user)
		(27 "Margin" user)
		(31 "F.CrtYd" user "F.Courtyard")
		(29 "B.CrtYd" user "B.Courtyard")
		(35 "F.Fab" user)
		(33 "B.Fab" user)
	)
	(footprint "antmicro-footprints:D_0402_1005Metric"
		(layer "B.Cu")
		(at 97.6 93.45 -90)
		(property "Reference" "D2"
			(at -2.45 -0.426 270)
			(layer "B.SilkS")
			(effects
				(font
					(size 0.7 0.7)
					(thickness 0.15)
				)
				(justify left bottom mirror)
			)
		)
		(property "Value" "AXGD10402KR"
			(at -2.54 -2.54 90)
			(layer "B.Fab")
			(effects
				(font
					(size 0.7 0.7)
					(thickness 0.15)
				)
				(justify left bottom mirror)
			)
		)
		(property "Datasheet" "https://www.littelfuse.com/media?resourcetype=datasheets&itemid=020b2bf2-064c-4ff1-a898-b4ec805b2fea&filename=littelfuse-xtremeguard-axgd-datasheet"
			(at 0 0 270)
			(layer "F.Fab")
			(hide yes)
			(effects
				(font
					(size 1.27 1.27)
					(thickness 0.15)
				)
			)
		)
		(property "Description" "Bidirectional TVS, 30 kV,  0402, 24 V, 0.04 pF"
			(at 0 0 270)
			(layer "F.Fab")
			(hide yes)
			(effects
				(font
					(size 1.27 1.27)
					(thickness 0.15)
				)
			)
		)
		(property "Manufacturer" "Littelfuse"
			(at 0 0 270)
			(unlocked yes)
			(layer "B.Fab")
			(hide yes)
			(effects
				(font
					(size 1 1)
					(thickness 0.15)
				)
				(justify mirror)
			)
		)
		(property "MPN" "AXGD10402KR"
			(at 0 0 270)
			(unlocked yes)
			(layer "B.Fab")
			(hide yes)
			(effects
				(font
					(size 1 1)
					(thickness 0.15)
				)
				(justify mirror)
			)
		)
		(property "Author" "Antmicro"
			(at 0 0 270)
			(unlocked yes)
			(layer "B.Fab")
			(hide yes)
			(effects
				(font
					(size 1 1)
					(thickness 0.15)
				)
				(justify mirror)
			)
		)
		(property "License" "Apache-2.0"
			(at 0 0 270)
			(unlocked yes)
			(layer "B.Fab")
			(hide yes)
			(effects
				(font
					(size 1 1)
					(thickness 0.15)
				)
				(justify mirror)
			)
		)
		(sheetname "/DC-DC Converters/")
		(sheetfile "dc-dc_converters.kicad_sch")
		(attr smd)
		(fp_line
			(start -0.1 0.255)
			(end 0.1 0.255)
			(stroke
				(width 0.15)
				(type solid)
			)
			(layer "B.SilkS")
		)
		(fp_line
			(start -0.875 -0.25)
			(end -0.875 0.25)
			(stroke
				(width 0.15)
				(type solid)
			)
			(layer "B.SilkS")
		)
		(fp_line
			(start 0.1 -0.255)
			(end -0.1 -0.255)
			(stroke
				(width 0.15)
				(type solid)
			)
			(layer "B.SilkS")
		)
		(fp_rect
			(start -0.925 0.47)
			(end 0.925 -0.47)
			(stroke
				(width 0.05)
				(type default)
			)
			(fill no)
			(layer "B.CrtYd")
		)
		(fp_line
			(start -0.51 0.255)
			(end -0.51 -0.255)
			(stroke
				(width 0.15)
				(type solid)
			)
			(layer "B.Fab")
		)
		(fp_line
			(start 0.51 0.255)
			(end -0.51 0.255)
			(stroke
				(width 0.15)
				(type solid)
			)
			(layer "B.Fab")
		)
		(fp_line
			(start -0.5 -0.05)
			(end -0.2 0.25)
			(stroke
				(width 0.15)
				(type solid)
			)
			(layer "B.Fab")
		)
		(fp_line
			(start -0.51 -0.255)
			(end 0.51 -0.255)
			(stroke
				(width 0.15)
				(type solid)
			)
			(layer "B.Fab")
		)
		(fp_line
			(start 0.51 -0.255)
			(end 0.51 0.255)
			(stroke
				(width 0.15)
				(type solid)
			)
			(layer "B.Fab")
		)
		(pad "1" smd roundrect
			(at -0.48 0 270)
			(size 0.59 0.64)
			(layers "B.Cu" "B.Mask" "B.Paste")
			(roundrect_rratio 0.25)
			(net 2 "GND")
			(pinfunction "C")
			(pintype "passive")
		)
		(pad "2" smd roundrect
			(at 0.48 0 270)
			(size 0.59 0.64)
			(layers "B.Cu" "B.Mask" "B.Paste")
			(roundrect_rratio 0.25)
			(net 5 "+12V")
			(pinfunction "A")
			(pintype "passive")
		)
	)
	(footprint "antmicro-footprints:C_1206_3216Metric"
		(layer "B.Cu")
		(at 93.5 97.85 90)
		(descr "Capacitor SMD 1206")
		(tags "capacitor SMD 1206")
		(property "Reference" "C31"
			(at 24.698 -7.138 180)
			(layer "B.SilkS")
			(effects
				(font
					(size 0.7 0.7)
					(thickness 0.15)
				)
				(justify left bottom mirror)
			)
		)
		(property "Value" "C_47u_25V_1206"
			(at 0 -2.101 90)
			(layer "B.Fab")
			(effects
				(font
					(size 0.7 0.7)
					(thickness 0.15)
				)
				(justify right bottom mirror)
			)
		)
		(property "Datasheet" "https://product.tdk.com/en/search/capacitor/ceramic/mlcc/info?part_no=C3216X5R1E476M160AC"
			(at 0 0 90)
			(layer "F.Fab")
			(hide yes)
			(effects
				(font
					(size 1.27 1.27)
					(thickness 0.15)
				)
			)
		)
		(property "Description" "SMD Multilayer Ceramic Capacitor, 47 µF, 25 V, 1206 [3216 Metric], ± 20%, X5R"
			(at 0 0 90)
			(layer "F.Fab")
			(hide yes)
			(effects
				(font
					(size 1.27 1.27)
					(thickness 0.15)
				)
			)
		)
		(property "MPN" "C3216X5R1E476M160AC"
			(at 0 0 90)
			(unlocked yes)
			(layer "B.Fab")
			(hide yes)
			(effects
				(font
					(size 1 1)
					(thickness 0.15)
				)
				(justify mirror)
			)
		)
		(property "Val" "47u"
			(at 0 0 90)
			(unlocked yes)
			(layer "B.Fab")
			(hide yes)
			(effects
				(font
					(size 1 1)
					(thickness 0.15)
				)
				(justify mirror)
			)
		)
		(property "Voltage" "25V"
			(at 0 0 90)
			(unlocked yes)
			(layer "B.Fab")
			(hide yes)
			(effects
				(font
					(size 1 1)
					(thickness 0.15)
				)
				(justify mirror)
			)
		)
		(property "Author" "Antmicro"
			(at 0 0 90)
			(unlocked yes)
			(layer "B.Fab")
			(hide yes)
			(effects
				(font
					(size 1 1)
					(thickness 0.15)
				)
				(justify mirror)
			)
		)
		(property "License" "Apache-2.0"
			(at 0 0 90)
			(unlocked yes)
			(layer "B.Fab")
			(hide yes)
			(effects
				(font
					(size 1 1)
					(thickness 0.15)
				)
				(justify mirror)
			)
		)
		(property "Manufacturer" "TDK"
			(at 0 0 90)
			(unlocked yes)
			(layer "B.Fab")
			(hide yes)
			(effects
				(font
					(size 1 1)
					(thickness 0.15)
				)
				(justify mirror)
			)
		)
		(property "Dielectric" "X5R"
			(at 0 0 90)
			(unlocked yes)
			(layer "B.Fab")
			(hide yes)
			(effects
				(font
					(size 1 1)
					(thickness 0.15)
				)
				(justify mirror)
			)
		)
		(property "Public" "False"
			(at 0 0 90)
			(unlocked yes)
			(layer "B.Fab")
			(hide yes)
			(effects
				(font
					(size 1 1)
					(thickness 0.15)
				)
				(justify mirror)
			)
		)
		(sheetname "/DC-DC Converters/")
		(sheetfile "dc-dc_converters.kicad_sch")
		(attr smd)
		(fp_line
			(start -0.8 -0.901)
			(end 0.8 -0.901)
			(stroke
				(width 0.15)
				(type solid)
			)
			(layer "B.SilkS")
		)
		(fp_line
			(start -0.8 0.899)
			(end 0.8 0.899)
			(stroke
				(width 0.15)
				(type solid)
			)
			(layer "B.SilkS")
		)
		(fp_rect
			(start -2.325 1.15)
			(end 2.325 -1.15)
			(stroke
				(width 0.05)
				(type default)
			)
			(fill no)
			(layer "B.CrtYd")
		)
		(fp_rect
			(start -1.6 0.799)
			(end 1.6 -0.801)
			(stroke
				(width 0.15)
				(type solid)
			)
			(fill no)
			(layer "B.Fab")
		)
		(pad "1" smd roundrect
			(at -1.5 -0.001 90)
			(size 1.15 1.8)
			(layers "B.Cu" "B.Mask" "B.Paste")
			(roundrect_rratio 0.25)
			(net 2 "GND")
			(pintype "passive")
		)
		(pad "2" smd roundrect
			(at 1.5 -0.001 90)
			(size 1.15 1.8)
			(layers "B.Cu" "B.Mask" "B.Paste")
			(roundrect_rratio 0.25)
			(net 5 "+12V")
			(pintype "passive")
		)
	)
	(footprint "antmicro-footprints:WSON-6-1EP_2x2mm_P0.65mm"
		(layer "B.Cu")
		(at 83.9 66.9)
		(property "Reference" "U7"
			(at -1.223 2.188 0)
			(layer "B.SilkS")
			(effects
				(font
					(size 0.7 0.7)
					(thickness 0.15)
				)
				(justify right bottom mirror)
			)
		)
		(property "Value" "TVS2200DRVR"
			(at 0 -2.2 0)
			(layer "B.Fab")
			(effects
				(font
					(size 0.7 0.7)
					(thickness 0.15)
				)
				(justify right bottom mirror)
			)
		)
		(property "Datasheet" "https://www.ti.com/lit/ds/symlink/tvs2200.pdf?ts=1712230685180&ref_url=https%253A%252F%252Fwww.ti.com%252Fproduct%252FTVS2200"
			(at 0 0 0)
			(layer "F.Fab")
			(hide yes)
			(effects
				(font
					(size 1.27 1.27)
					(thickness 0.15)
				)
			)
		)
		(property "Description" "ESD Protection Device, 1 kV, WSON-6, 22 V, 105 pF"
			(at 0 0 0)
			(layer "F.Fab")
			(hide yes)
			(effects
				(font
					(size 1.27 1.27)
					(thickness 0.15)
				)
			)
		)
		(property "MPN" "TVS2200DRVR"
			(at 0 0 0)
			(unlocked yes)
			(layer "B.Fab")
			(hide yes)
			(effects
				(font
					(size 1 1)
					(thickness 0.15)
				)
				(justify mirror)
			)
		)
		(property "Manufacturer" "Texas Instruments"
			(at 0 0 0)
			(unlocked yes)
			(layer "B.Fab")
			(hide yes)
			(effects
				(font
					(size 1 1)
					(thickness 0.15)
				)
				(justify mirror)
			)
		)
		(property "License" "Apache-2.0"
			(at 0 0 0)
			(unlocked yes)
			(layer "B.Fab")
			(hide yes)
			(effects
				(font
					(size 1 1)
					(thickness 0.15)
				)
				(justify mirror)
			)
		)
		(property "Author" "Antmicro"
			(at 0 0 0)
			(unlocked yes)
			(layer "B.Fab")
			(hide yes)
			(effects
				(font
					(size 1 1)
					(thickness 0.15)
				)
				(justify mirror)
			)
		)
		(sheetname "/USB PD/")
		(sheetfile "usb_pd.kicad_sch")
		(attr smd)
		(fp_line
			(start -1.05 1)
			(end 1 1)
			(stroke
				(width 0.12)
				(type solid)
			)
			(layer "B.SilkS")
		)
		(fp_line
			(start 1 -1)
			(end -1 -1)
			(stroke
				(width 0.12)
				(type solid)
			)
			(layer "B.SilkS")
		)
		(fp_circle
			(center -1.275 1.075)
			(end -1.224 1.075)
			(stroke
				(width 0.15)
				(type solid)
			)
			(fill yes)
			(layer "B.SilkS")
		)
		(fp_rect
			(start -1.45 1.25)
			(end 1.45 -1.25)
			(stroke
				(width 0.05)
				(type solid)
			)
			(fill no)
			(layer "B.CrtYd")
		)
		(pad "1" smd roundrect
			(at -0.975 0.652)
			(size 0.45 0.4)
			(layers "B.Cu" "B.Mask" "B.Paste")
			(roundrect_rratio 0.25)
			(net 2 "GND")
			(pinfunction "GND")
			(pintype "passive")
		)
		(pad "2" smd roundrect
			(at -0.975 0)
			(size 0.45 0.4)
			(layers "B.Cu" "B.Mask" "B.Paste")
			(roundrect_rratio 0.25)
			(net 2 "GND")
			(pinfunction "GND")
			(pintype "passive")
		)
		(pad "3" smd roundrect
			(at -0.975 -0.65)
			(size 0.45 0.4)
			(layers "B.Cu" "B.Mask" "B.Paste")
			(roundrect_rratio 0.25)
			(net 2 "GND")
			(pinfunction "GND")
			(pintype "passive")
		)
		(pad "4" smd roundrect
			(at 0.973 -0.65)
			(size 0.45 0.4)
			(layers "B.Cu" "B.Mask" "B.Paste")
			(roundrect_rratio 0.25)
			(net 29 "/USB PD/CC1")
			(pinfunction "IN")
			(pintype "passive")
		)
		(pad "5" smd roundrect
			(at 0.973 0)
			(size 0.45 0.4)
			(layers "B.Cu" "B.Mask" "B.Paste")
			(roundrect_rratio 0.25)
			(net 29 "/USB PD/CC1")
			(pinfunction "IN")
			(pintype "passive")
		)
		(pad "6" smd roundrect
			(at 0.973 0.652)
			(size 0.45 0.4)
			(layers "B.Cu" "B.Mask" "B.Paste")
			(roundrect_rratio 0.25)
			(net 29 "/USB PD/CC1")
			(pinfunction "IN")
			(pintype "passive")
		)
		(pad "7" smd roundrect
			(at 0 0)
			(size 1.12 1.72)
			(layers "B.Cu" "B.Mask" "B.Paste")
			(roundrect_rratio 0.1)
			(net 2 "GND")
			(pinfunction "GND")
			(pintype "passive")
		)
	)
	(footprint "antmicro-footprints:C_0402_1005Metric"
		(layer "B.Cu")
		(at 86.451 86.7 -90)
		(descr "Capacitor SMD 0402")
		(tags "capacitor SMD 0402")
		(property "Reference" "C23"
			(at -1.083 -3.11 90)
			(layer "B.SilkS")
			(effects
				(font
					(size 0.7 0.7)
					(thickness 0.15)
				)
				(justify left bottom mirror)
			)
		)
		(property "Value" "C_100n_50V_X8L_0402"
			(at -1.022927 -2.155213 90)
			(layer "B.Fab")
			(effects
				(font
					(size 0.7 0.7)
					(thickness 0.15)
				)
				(justify left bottom mirror)
			)
		)
		(property "Datasheet" "https://www.murata.com/products/productdetail?partno=GCM155L8EH104KE07%23"
			(at 0 0 270)
			(layer "F.Fab")
			(hide yes)
			(effects
				(font
					(size 1.27 1.27)
					(thickness 0.15)
				)
			)
		)
		(property "Description" "SMD Multilayer Ceramic Capacitor, 100nF, 50V, 0402, ±10%, X8L"
			(at 0 0 270)
			(layer "F.Fab")
			(hide yes)
			(effects
				(font
					(size 1.27 1.27)
					(thickness 0.15)
				)
			)
		)
		(property "MPN" "GCM155L8EH104KE07D"
			(at 0 0 270)
			(unlocked yes)
			(layer "B.Fab")
			(hide yes)
			(effects
				(font
					(size 1 1)
					(thickness 0.15)
				)
				(justify mirror)
			)
		)
		(property "Val" "100n"
			(at 0 0 270)
			(unlocked yes)
			(layer "B.Fab")
			(hide yes)
			(effects
				(font
					(size 1 1)
					(thickness 0.15)
				)
				(justify mirror)
			)
		)
		(property "Voltage" "50V"
			(at 0 0 270)
			(unlocked yes)
			(layer "B.Fab")
			(hide yes)
			(effects
				(font
					(size 1 1)
					(thickness 0.15)
				)
				(justify mirror)
			)
		)
		(property "Dielectric" "X8L"
			(at 0 0 270)
			(unlocked yes)
			(layer "B.Fab")
			(hide yes)
			(effects
				(font
					(size 1 1)
					(thickness 0.15)
				)
				(justify mirror)
			)
		)
		(property "Manufacturer" "Murata"
			(at 0 0 270)
			(unlocked yes)
			(layer "B.Fab")
			(hide yes)
			(effects
				(font
					(size 1 1)
					(thickness 0.15)
				)
				(justify mirror)
			)
		)
		(property "License" "Apache-2.0"
			(at 0 0 270)
			(unlocked yes)
			(layer "B.Fab")
			(hide yes)
			(effects
				(font
					(size 1 1)
					(thickness 0.15)
				)
				(justify mirror)
			)
		)
		(property "Author" "Antmicro"
			(at 0 0 270)
			(unlocked yes)
			(layer "B.Fab")
			(hide yes)
			(effects
				(font
					(size 1 1)
					(thickness 0.15)
				)
				(justify mirror)
			)
		)
		(sheetname "/DC-DC Converters/")
		(sheetfile "dc-dc_converters.kicad_sch")
		(attr smd)
		(fp_rect
			(start -0.925 0.47)
			(end 0.925 -0.47)
			(stroke
				(width 0.05)
				(type default)
			)
			(fill no)
			(layer "B.CrtYd")
		)
		(fp_line
			(start -0.494 0.25)
			(end -0.494 -0.248)
			(stroke
				(width 0.15)
				(type solid)
			)
			(layer "B.Fab")
		)
		(fp_line
			(start 0.504 0.25)
			(end -0.494 0.25)
			(stroke
				(width 0.15)
				(type solid)
			)
			(layer "B.Fab")
		)
		(fp_line
			(start -0.494 -0.248)
			(end 0.504 -0.248)
			(stroke
				(width 0.15)
				(type solid)
			)
			(layer "B.Fab")
		)
		(fp_line
			(start 0.504 -0.248)
			(end 0.504 0.25)
			(stroke
				(width 0.15)
				(type solid)
			)
			(layer "B.Fab")
		)
		(pad "1" smd roundrect
			(at -0.48 0 270)
			(size 0.59 0.64)
			(layers "B.Cu" "B.Mask" "B.Paste")
			(roundrect_rratio 0.25)
			(net 21 "Net-(U3-SW)")
			(pintype "passive")
		)
		(pad "2" smd roundrect
			(at 0.48 0 270)
			(size 0.59 0.64)
			(layers "B.Cu" "B.Mask" "B.Paste")
			(roundrect_rratio 0.25)
			(net 22 "Net-(U3-BST)")
			(pintype "passive")
		)
	)
	(footprint "antmicro-footprints:R_0402_1005Metric"
		(layer "B.Cu")
		(at 87.625 82.9 90)
		(descr "Resistor SMD 0402")
		(tags "resistor SMD 0402")
		(property "Reference" "R1"
			(at 1.0612 2.374 270)
			(layer "B.SilkS")
			(effects
				(font
					(size 0.7 0.7)
					(thickness 0.15)
				)
				(justify left bottom mirror)
			)
		)
		(property "Value" "R_3k16_0402"
			(at -1.011843 -1.772047 90)
			(layer "B.Fab")
			(effects
				(font
					(size 0.7 0.7)
					(thickness 0.15)
				)
				(justify right bottom mirror)
			)
		)
		(property "Datasheet" "https://www.mouser.com/datasheet/2/447/YAGEO_PYu_RC_Group_51_RoHS_L_12-3313492.pdf"
			(at 0 0 90)
			(layer "F.Fab")
			(hide yes)
			(effects
				(font
					(size 1.27 1.27)
					(thickness 0.15)
				)
			)
		)
		(property "Description" "SMD Chip Resistor, 3.16 kohm, ± 1%, 62.5 mW, 0402 [1005 Metric], Thick Film, General Purpose"
			(at 0 0 90)
			(layer "F.Fab")
			(hide yes)
			(effects
				(font
					(size 1.27 1.27)
					(thickness 0.15)
				)
			)
		)
		(property "MPN" "RC0402FR-073K16L"
			(at 0 0 90)
			(unlocked yes)
			(layer "B.Fab")
			(hide yes)
			(effects
				(font
					(size 1 1)
					(thickness 0.15)
				)
				(justify mirror)
			)
		)
		(property "Val" "3k16"
			(at 0 0 90)
			(unlocked yes)
			(layer "B.Fab")
			(hide yes)
			(effects
				(font
					(size 1 1)
					(thickness 0.15)
				)
				(justify mirror)
			)
		)
		(property "License" "Apache-2.0"
			(at 0 0 90)
			(unlocked yes)
			(layer "B.Fab")
			(hide yes)
			(effects
				(font
					(size 1 1)
					(thickness 0.15)
				)
				(justify mirror)
			)
		)
		(property "Manufacturer" "YAGEO"
			(at 0 0 90)
			(unlocked yes)
			(layer "B.Fab")
			(hide yes)
			(effects
				(font
					(size 1 1)
					(thickness 0.15)
				)
				(justify mirror)
			)
		)
		(property "Tolerance" "1%"
			(at 0 0 90)
			(unlocked yes)
			(layer "B.Fab")
			(hide yes)
			(effects
				(font
					(size 1 1)
					(thickness 0.15)
				)
				(justify mirror)
			)
		)
		(property "Author" "Antmicro"
			(at 0 0 90)
			(unlocked yes)
			(layer "B.Fab")
			(hide yes)
			(effects
				(font
					(size 1 1)
					(thickness 0.15)
				)
				(justify mirror)
			)
		)
		(sheetname "/DC-DC Converters/")
		(sheetfile "dc-dc_converters.kicad_sch")
		(attr smd)
		(fp_rect
			(start -0.925 0.47)
			(end 0.925 -0.47)
			(stroke
				(width 0.05)
				(type default)
			)
			(fill no)
			(layer "B.CrtYd")
		)
		(fp_rect
			(start -0.5 0.25)
			(end 0.5 -0.25)
			(stroke
				(width 0.15)
				(type solid)
			)
			(fill no)
			(layer "B.Fab")
		)
		(pad "1" smd roundrect
			(at -0.48 0 90)
			(size 0.59 0.64)
			(layers "B.Cu" "B.Mask" "B.Paste")
			(roundrect_rratio 0.25)
			(net 39 "Net-(U4-FB)")
			(pintype "passive")
		)
		(pad "2" smd roundrect
			(at 0.48 0 90)
			(size 0.59 0.64)
			(layers "B.Cu" "B.Mask" "B.Paste")
			(roundrect_rratio 0.25)
			(net 1 "+3V3")
			(pintype "passive")
		)
	)
)
